# SCM (Grand Teton) — schematic netlist excerpt (pin names and nets, part order shuffled) for the footprints in the layout excerpt that follows; sources: Cadence DE-HDL packaged netlist, KiCad conversion of 12092022_DA0F0TMDCD0_F0T_Management_Board_D_brd_V3_OCP.brd

D19  Q_LED  IC  pkg SMLF  page 49 : A = P3V3_AUX ; C = FM_UARTSW_MSB_R1_N
C29  Q_CAP  0.1UF 25V 10% EMPTY  pkg 0402  page 50 : A = P3V3_AUX ; B = GND

(kicad_pcb
	(version 20260206)
	(generator "pcbnew")
	(generator_version "10.0")
	(general
		(thickness 1.6)
		(legacy_teardrops no)
	)
	(paper "A4")
	(title_block
		(title "12092022_DA0F0TMDCD0_F0T_Management_Board_D_brd_V3_OCP.brd")
		(comment 1 "Grand Teton / footprints 677-678 of 1440")
	)
	(layers
		(0 "F.Cu" signal "TOP")
		(4 "In1.Cu" signal "GND")
		(6 "In2.Cu" signal "IN1")
		(8 "In3.Cu" signal "GND1")
		(10 "In4.Cu" signal "IN2")
		(12 "In5.Cu" signal "VCC")
		(14 "In6.Cu" signal "VCC1")
		(16 "In7.Cu" signal "IN3")
		(18 "In8.Cu" signal "GND2")
		(20 "In9.Cu" signal "IN4")
		(22 "In10.Cu" signal "GND3")
		(2 "B.Cu" signal "BOTTOM")
		(9 "F.Adhes" user "F.Adhesive")
		(11 "B.Adhes" user "B.Adhesive")
		(13 "F.Paste" user "Package Geometry/Pastemask Top")
		(15 "B.Paste" user "Package Geometry/Pastemask Bottom")
		(5 "F.SilkS" user "Ref Des/Silkscreen Top")
		(7 "B.SilkS" user "Ref Des/Silkscreen Bottom")
		(1 "F.Mask" user "Board Geometry/Soldermask Top")
		(3 "B.Mask" user "Board Geometry/Soldermask Bottom")
		(17 "Dwgs.User" user "User.Drawings")
		(19 "Cmts.User" user "User.Comments")
		(21 "Eco1.User" user "User.Eco1")
		(23 "Eco2.User" user "User.Eco2")
		(25 "Edge.Cuts" user "Board Geometry/Outline")
		(27 "Margin" user)
		(31 "F.CrtYd" user "Package Geometry/Place Bound Top")
		(29 "B.CrtYd" user "Package Geometry/Place Bound Bottom")
		(35 "F.Fab" user "Ref Des/Assembly Top")
		(33 "B.Fab" user "Ref Des/Assembly Bottom")
	)
	(footprint ""
		(layer "F.Cu")
		(at 76.708 -14.478)
		(property "Reference" "C29"
			(at 0 0 0)
			(layer "F.SilkS")
			(hide yes)
			(effects
				(font
					(size 1.27 1.27)
				)
			)
		)
		(property "Value" ""
			(at 0 0 0)
			(layer "F.Fab")
			(effects
				(font
					(size 1.27 1.27)
				)
			)
		)
		(duplicate_pad_numbers_are_jumpers no)
		(fp_line
			(start -0.7874 -0.4064)
			(end 0.7874 -0.4064)
			(stroke
				(width 0.1524)
				(type default)
			)
			(layer "F.SilkS")
		)
		(fp_line
			(start -0.7874 0.4064)
			(end -0.7874 -0.4064)
			(stroke
				(width 0.1524)
				(type default)
			)
			(layer "F.SilkS")
		)
		(fp_line
			(start 0.7874 -0.4064)
			(end 0.7874 0.4064)
			(stroke
				(width 0.1524)
				(type default)
			)
			(layer "F.SilkS")
		)
		(fp_line
			(start 0.7874 0.4064)
			(end -0.7874 0.4064)
			(stroke
				(width 0.1524)
				(type default)
			)
			(layer "F.SilkS")
		)
		(fp_line
			(start -0.67945 -0.305054)
			(end -0.12065 -0.305054)
			(stroke
				(width 0.1)
				(type default)
			)
			(layer "F.Fab")
		)
		(fp_line
			(start -0.67945 0.3048)
			(end -0.67945 -0.305054)
			(stroke
				(width 0.1)
				(type default)
			)
			(layer "F.Fab")
		)
		(fp_line
			(start -0.12065 -0.305054)
			(end -0.12065 -0.2794)
			(stroke
				(width 0.1)
				(type default)
			)
			(layer "F.Fab")
		)
		(fp_line
			(start -0.12065 -0.2794)
			(end 0.12065 -0.2794)
			(stroke
				(width 0.1)
				(type default)
			)
			(layer "F.Fab")
		)
		(fp_line
			(start -0.12065 0.2794)
			(end -0.12065 0.3048)
			(stroke
				(width 0.1)
				(type default)
			)
			(layer "F.Fab")
		)
		(fp_line
			(start -0.12065 0.3048)
			(end -0.67945 0.3048)
			(stroke
				(width 0.1)
				(type default)
			)
			(layer "F.Fab")
		)
		(fp_line
			(start 0.120396 0.2794)
			(end -0.12065 0.2794)
			(stroke
				(width 0.1)
				(type default)
			)
			(layer "F.Fab")
		)
		(fp_line
			(start 0.120396 0.3048)
			(end 0.120396 0.2794)
			(stroke
				(width 0.1)
				(type default)
			)
			(layer "F.Fab")
		)
		(fp_line
			(start 0.12065 -0.3048)
			(end 0.67945 -0.3048)
			(stroke
				(width 0.1)
				(type default)
			)
			(layer "F.Fab")
		)
		(fp_line
			(start 0.12065 -0.2794)
			(end 0.12065 -0.3048)
			(stroke
				(width 0.1)
				(type default)
			)
			(layer "F.Fab")
		)
		(fp_line
			(start 0.67945 -0.3048)
			(end 0.67945 0.3048)
			(stroke
				(width 0.1)
				(type default)
			)
			(layer "F.Fab")
		)
		(fp_line
			(start 0.67945 0.3048)
			(end 0.120396 0.3048)
			(stroke
				(width 0.1)
				(type default)
			)
			(layer "F.Fab")
		)
		(pad "1" smd circle
			(at -0.40005 0)
			(size 0 0)
			(layers "F.Cu" "F.Mask" "F.Paste")
			(net "P3V3_AUX")
		)
		(pad "2" smd circle
			(at 0.40005 0)
			(size 0 0)
			(layers "F.Cu" "F.Mask" "F.Paste")
			(net "GND")
		)
	)
	(footprint ""
		(layer "F.Cu")
		(at 77.47 -21.336 180)
		(property "Reference" "D19"
			(at 1.143 1.11633 0)
			(unlocked yes)
			(layer "F.SilkS")
			(effects
				(font
					(size 0.7874 0.5842)
					(thickness 0.1524)
				)
				(justify left)
			)
		)
		(property "Value" ""
			(at 0 0 180)
			(layer "F.Fab")
			(effects
				(font
					(size 1.27 1.27)
				)
			)
		)
		(duplicate_pad_numbers_are_jumpers no)
		(fp_line
			(start 1.16078 0.4826)
			(end -0.64008 0.4826)
			(stroke
				(width 0.1524)
				(type default)
			)
			(layer "F.SilkS")
		)
		(fp_line
			(start 1.16078 -0.4826)
			(end 1.16078 0.4826)
			(stroke
				(width 0.1524)
				(type default)
			)
			(layer "F.SilkS")
		)
		(fp_line
			(start 1.03378 0.4826)
			(end -0.79248 0.4826)
			(stroke
				(width 0.1524)
				(type default)
			)
			(layer "F.SilkS")
		)
		(fp_line
			(start 1.03378 -0.4826)
			(end 1.03378 0.4826)
			(stroke
				(width 0.1524)
				(type default)
			)
			(layer "F.SilkS")
		)
		(fp_line
			(start 0.90678 0.4826)
			(end -0.90678 0.4826)
			(stroke
				(width 0.1524)
				(type default)
			)
			(layer "F.SilkS")
		)
		(fp_line
			(start 0.90678 -0.4826)
			(end 0.90678 0.4826)
			(stroke
				(width 0.1524)
				(type default)
			)
			(layer "F.SilkS")
		)
		(fp_line
			(start -0.64008 -0.4826)
			(end 1.16078 -0.4826)
			(stroke
				(width 0.1524)
				(type default)
			)
			(layer "F.SilkS")
		)
		(fp_line
			(start -0.79248 -0.4826)
			(end 1.03378 -0.4826)
			(stroke
				(width 0.1524)
				(type default)
			)
			(layer "F.SilkS")
		)
		(fp_line
			(start -0.89408 -0.4826)
			(end 0.90678 -0.4826)
			(stroke
				(width 0.1524)
				(type default)
			)
			(layer "F.SilkS")
		)
		(fp_line
			(start -0.90678 0.4826)
			(end -0.90678 -0.4699)
			(stroke
				(width 0.1524)
				(type default)
			)
			(layer "F.SilkS")
		)
		(fp_line
			(start 0.499872 0.249936)
			(end -0.499872 0.249936)
			(stroke
				(width 0.1)
				(type default)
			)
			(layer "F.Fab")
		)
		(fp_line
			(start 0.499872 -0.249936)
			(end 0.499872 0.249936)
			(stroke
				(width 0.1)
				(type default)
			)
			(layer "F.Fab")
		)
		(fp_line
			(start -0.499872 0.249936)
			(end -0.499872 -0.249936)
			(stroke
				(width 0.1)
				(type default)
			)
			(layer "F.Fab")
		)
		(fp_line
			(start -0.499872 -0.249936)
			(end 0.499872 -0.249936)
			(stroke
				(width 0.1)
				(type default)
			)
			(layer "F.Fab")
		)
		(pad "A" smd rect
			(at -0.47498 0 180)
			(size 0.6096 0.7112)
			(layers "F.Cu" "F.Mask" "F.Paste")
			(net "P3V3_AUX")
		)
		(pad "C" smd rect
			(at 0.47498 0 180)
			(size 0.6096 0.7112)
			(layers "F.Cu" "F.Mask" "F.Paste")
			(net "FM_UARTSW_MSB_R1_N")
		)
	)
)
